# T6G (Grand Teton) — schematic netlist excerpt (pin names and nets, part order shuffled) for the footprints in the layout excerpt that follows; sources: Cadence DE-HDL packaged netlist, KiCad conversion of 04192023_DAF0TMB3IC0_F0TG_MB_C_brd_V02_OCP.brd

C2626  Q_CAP  22UF 4V 20% X6S  pkg C0402  page 70 : A = PVDDIO_P0 ; B = GND
R1896  Q_RES  100 1% CHIP  pkg 0402LF  page 132 : A = OCP_SFF_ISO_BIF0_EN ; B = GND
C394  Q_CAP  1UF 4V 20% X6S  pkg 0201  page 345 : A = P0V9_CPU1_RT2_2A_2D ; B = GND

(kicad_pcb
	(version 20260206)
	(generator "pcbnew")
	(generator_version "10.0")
	(general
		(thickness 1.6)
		(legacy_teardrops no)
	)
	(paper "A4")
	(title_block
		(title "04192023_DAF0TMB3IC0_F0TG_MB_C_brd_V02_OCP.brd")
		(comment 1 "Grand Teton / footprints 8213-8215 of 8354")
	)
	(layers
		(0 "F.Cu" signal "TOP")
		(4 "In1.Cu" signal "GND")
		(6 "In2.Cu" signal "IN1")
		(8 "In3.Cu" signal "GND1")
		(10 "In4.Cu" signal "IN2")
		(12 "In5.Cu" signal "GND2")
		(14 "In6.Cu" signal "IN3")
		(16 "In7.Cu" signal "GND3")
		(18 "In8.Cu" signal "VCC")
		(20 "In9.Cu" signal "VCC1")
		(22 "In10.Cu" signal "GND4")
		(24 "In11.Cu" signal "IN4")
		(26 "In12.Cu" signal "GND5")
		(28 "In13.Cu" signal "IN5")
		(30 "In14.Cu" signal "GND6")
		(32 "In15.Cu" signal "IN6")
		(34 "In16.Cu" signal "GND7")
		(2 "B.Cu" signal "BOTTOM")
		(9 "F.Adhes" user "F.Adhesive")
		(11 "B.Adhes" user "B.Adhesive")
		(13 "F.Paste" user "Package Geometry/Pastemask Top")
		(15 "B.Paste" user "Package Geometry/Pastemask Bottom")
		(5 "F.SilkS" user "Ref Des/Silkscreen Top")
		(7 "B.SilkS" user "Ref Des/Silkscreen Bottom")
		(1 "F.Mask" user "Board Geometry/Soldermask Top")
		(3 "B.Mask" user "Board Geometry/Soldermask Bottom")
		(17 "Dwgs.User" user "User.Drawings")
		(19 "Cmts.User" user "User.Comments")
		(21 "Eco1.User" user "User.Eco1")
		(23 "Eco2.User" user "User.Eco2")
		(25 "Edge.Cuts" user "Board Geometry/Outline")
		(27 "Margin" user)
		(31 "F.CrtYd" user "Package Geometry/Place Bound Top")
		(29 "B.CrtYd" user "Package Geometry/Place Bound Bottom")
		(35 "F.Fab" user "Ref Des/Assembly Top")
		(33 "B.Fab" user "Ref Des/Assembly Bottom")
	)
	(footprint ""
		(layer "B.Cu")
		(at 160.206182 -386.766562 90)
		(property "Reference" "C394"
			(at 0 0 90)
			(layer "B.SilkS")
			(hide yes)
			(effects
				(font
					(size 1.27 1.27)
				)
				(justify mirror)
			)
		)
		(property "Value" ""
			(at 0 0 90)
			(layer "B.Fab")
			(effects
				(font
					(size 1.27 1.27)
				)
				(justify mirror)
			)
		)
		(duplicate_pad_numbers_are_jumpers no)
		(fp_line
			(start 0.299974 -0.150114)
			(end -0.299974 -0.150114)
			(stroke
				(width 0.1)
				(type default)
			)
			(layer "B.Fab")
		)
		(fp_line
			(start -0.299974 -0.150114)
			(end -0.299974 0.150114)
			(stroke
				(width 0.1)
				(type default)
			)
			(layer "B.Fab")
		)
		(fp_line
			(start 0.299974 0.150114)
			(end 0.299974 -0.150114)
			(stroke
				(width 0.1)
				(type default)
			)
			(layer "B.Fab")
		)
		(fp_line
			(start -0.299974 0.150114)
			(end 0.299974 0.150114)
			(stroke
				(width 0.1)
				(type default)
			)
			(layer "B.Fab")
		)
		(pad "1" smd rect
			(at 0.2667 0 270)
			(size 0.3048 0.381)
			(layers "B.Cu" "B.Mask" "B.Paste")
			(net "P0V9_CPU1_RT2_2A_2D")
		)
		(pad "2" smd rect
			(at -0.2667 0 270)
			(size 0.3048 0.381)
			(layers "B.Cu" "B.Mask" "B.Paste")
			(net "GND")
		)
	)
	(footprint ""
		(layer "B.Cu")
		(at 348.151958 -265.045952)
		(property "Reference" "C2626"
			(at 0 0 0)
			(layer "B.SilkS")
			(hide yes)
			(effects
				(font
					(size 1.27 1.27)
				)
				(justify mirror)
			)
		)
		(property "Value" ""
			(at 0 0 0)
			(layer "B.Fab")
			(effects
				(font
					(size 1.27 1.27)
				)
				(justify mirror)
			)
		)
		(duplicate_pad_numbers_are_jumpers no)
		(fp_line
			(start -0.7874 -0.4064)
			(end -0.7874 0.4064)
			(stroke
				(width 0.1524)
				(type default)
			)
			(layer "B.SilkS")
		)
		(fp_line
			(start -0.7874 0.4064)
			(end 0.7874 0.4064)
			(stroke
				(width 0.1524)
				(type default)
			)
			(layer "B.SilkS")
		)
		(fp_line
			(start 0.7874 -0.4064)
			(end -0.7874 -0.4064)
			(stroke
				(width 0.1524)
				(type default)
			)
			(layer "B.SilkS")
		)
		(fp_line
			(start 0.7874 0.4064)
			(end 0.7874 -0.4064)
			(stroke
				(width 0.1524)
				(type default)
			)
			(layer "B.SilkS")
		)
		(fp_line
			(start -0.67945 -0.3048)
			(end -0.67945 0.3048)
			(stroke
				(width 0.1)
				(type default)
			)
			(layer "B.Fab")
		)
		(fp_line
			(start -0.67945 0.3048)
			(end -0.120396 0.3048)
			(stroke
				(width 0.1)
				(type default)
			)
			(layer "B.Fab")
		)
		(fp_line
			(start -0.12065 -0.3048)
			(end -0.67945 -0.3048)
			(stroke
				(width 0.1)
				(type default)
			)
			(layer "B.Fab")
		)
		(fp_line
			(start -0.12065 -0.2794)
			(end -0.12065 -0.3048)
			(stroke
				(width 0.1)
				(type default)
			)
			(layer "B.Fab")
		)
		(fp_line
			(start -0.120396 0.2794)
			(end 0.12065 0.2794)
			(stroke
				(width 0.1)
				(type default)
			)
			(layer "B.Fab")
		)
		(fp_line
			(start -0.120396 0.3048)
			(end -0.120396 0.2794)
			(stroke
				(width 0.1)
				(type default)
			)
			(layer "B.Fab")
		)
		(fp_line
			(start 0.12065 -0.305054)
			(end 0.12065 -0.2794)
			(stroke
				(width 0.1)
				(type default)
			)
			(layer "B.Fab")
		)
		(fp_line
			(start 0.12065 -0.2794)
			(end -0.12065 -0.2794)
			(stroke
				(width 0.1)
				(type default)
			)
			(layer "B.Fab")
		)
		(fp_line
			(start 0.12065 0.2794)
			(end 0.12065 0.3048)
			(stroke
				(width 0.1)
				(type default)
			)
			(layer "B.Fab")
		)
		(fp_line
			(start 0.12065 0.3048)
			(end 0.67945 0.3048)
			(stroke
				(width 0.1)
				(type default)
			)
			(layer "B.Fab")
		)
		(fp_line
			(start 0.67945 -0.305054)
			(end 0.12065 -0.305054)
			(stroke
				(width 0.1)
				(type default)
			)
			(layer "B.Fab")
		)
		(fp_line
			(start 0.67945 0.3048)
			(end 0.67945 -0.305054)
			(stroke
				(width 0.1)
				(type default)
			)
			(layer "B.Fab")
		)
		(pad "1" smd circle
			(at 0.40005 0 180)
			(size 0 0)
			(layers "B.Cu" "B.Mask" "B.Paste")
			(net "PVDDIO_P0")
		)
		(pad "2" smd circle
			(at -0.40005 0 180)
			(size 0 0)
			(layers "B.Cu" "B.Mask" "B.Paste")
			(net "GND")
		)
	)
	(footprint ""
		(layer "B.Cu")
		(at 438.013348 -19.07667 -90)
		(property "Reference" "R1896"
			(at 0 0 90)
			(layer "B.SilkS")
			(hide yes)
			(effects
				(font
					(size 1.27 1.27)
				)
				(justify mirror)
			)
		)
		(property "Value" ""
			(at 0 0 90)
			(layer "B.Fab")
			(effects
				(font
					(size 1.27 1.27)
				)
				(justify mirror)
			)
		)
		(duplicate_pad_numbers_are_jumpers no)
		(fp_line
			(start -0.7874 0.4064)
			(end 0.7874 0.4064)
			(stroke
				(width 0.1524)
				(type default)
			)
			(layer "B.SilkS")
		)
		(fp_line
			(start 0.7874 0.4064)
			(end 0.7874 -0.4064)
			(stroke
				(width 0.1524)
				(type default)
			)
			(layer "B.SilkS")
		)
		(fp_line
			(start -0.7874 -0.4064)
			(end -0.7874 0.4064)
			(stroke
				(width 0.1524)
				(type default)
			)
			(layer "B.SilkS")
		)
		(fp_line
			(start 0.7874 -0.4064)
			(end -0.7874 -0.4064)
			(stroke
				(width 0.1524)
				(type default)
			)
			(layer "B.SilkS")
		)
		(fp_line
			(start -0.67945 0.3048)
			(end -0.120396 0.3048)
			(stroke
				(width 0.1)
				(type default)
			)
			(layer "B.Fab")
		)
		(fp_line
			(start -0.120396 0.3048)
			(end -0.120396 0.2794)
			(stroke
				(width 0.1)
				(type default)
			)
			(layer "B.Fab")
		)
		(fp_line
			(start 0.12065 0.3048)
			(end 0.67945 0.3048)
			(stroke
				(width 0.1)
				(type default)
			)
			(layer "B.Fab")
		)
		(fp_line
			(start 0.67945 0.3048)
			(end 0.67945 -0.305054)
			(stroke
				(width 0.1)
				(type default)
			)
			(layer "B.Fab")
		)
		(fp_line
			(start -0.120396 0.2794)
			(end 0.12065 0.2794)
			(stroke
				(width 0.1)
				(type default)
			)
			(layer "B.Fab")
		)
		(fp_line
			(start 0.12065 0.2794)
			(end 0.12065 0.3048)
			(stroke
				(width 0.1)
				(type default)
			)
			(layer "B.Fab")
		)
		(fp_line
			(start -0.12065 -0.2794)
			(end -0.12065 -0.3048)
			(stroke
				(width 0.1)
				(type default)
			)
			(layer "B.Fab")
		)
		(fp_line
			(start 0.12065 -0.2794)
			(end -0.12065 -0.2794)
			(stroke
				(width 0.1)
				(type default)
			)
			(layer "B.Fab")
		)
		(fp_line
			(start -0.67945 -0.3048)
			(end -0.67945 0.3048)
			(stroke
				(width 0.1)
				(type default)
			)
			(layer "B.Fab")
		)
		(fp_line
			(start -0.12065 -0.3048)
			(end -0.67945 -0.3048)
			(stroke
				(width 0.1)
				(type default)
			)
			(layer "B.Fab")
		)
		(fp_line
			(start 0.12065 -0.305054)
			(end 0.12065 -0.2794)
			(stroke
				(width 0.1)
				(type default)
			)
			(layer "B.Fab")
		)
		(fp_line
			(start 0.67945 -0.305054)
			(end 0.12065 -0.305054)
			(stroke
				(width 0.1)
				(type default)
			)
			(layer "B.Fab")
		)
		(pad "1" smd circle
			(at 0.40005 0 90)
			(size 0 0)
			(layers "B.Cu" "B.Mask" "B.Paste")
			(net "OCP_SFF_ISO_BIF0_EN")
		)
		(pad "2" smd circle
			(at -0.40005 0 90)
			(size 0 0)
			(layers "B.Cu" "B.Mask" "B.Paste")
			(net "GND")
		)
	)
)
